(kicad_pcb
	(version 20260206)
	(generator "pcbnew")
	(generator_version "10.0")
	(general
		(thickness 1.6)
		(legacy_teardrops no)
	)
	(paper "A4")
	(title_block
		(title "03242023_DA0F0TMBIJ0_F0T_Motherboard_J_brd_V01_OCP.brd")
		(comment 1 "Grand Teton / footprints 5768-5774 of 6105")
	)
	(layers
		(0 "F.Cu" signal "TOP")
		(4 "In1.Cu" signal "GND")
		(6 "In2.Cu" signal "IN1")
		(8 "In3.Cu" signal "GND1")
		(10 "In4.Cu" signal "IN2")
		(12 "In5.Cu" signal "GND2")
		(14 "In6.Cu" signal "IN3")
		(16 "In7.Cu" signal "GND3")
		(18 "In8.Cu" signal "VCC")
		(20 "In9.Cu" signal "VCC1")
		(22 "In10.Cu" signal "GND4")
		(24 "In11.Cu" signal "IN4")
		(26 "In12.Cu" signal "GND5")
		(28 "In13.Cu" signal "IN5")
		(30 "In14.Cu" signal "GND6")
		(32 "In15.Cu" signal "IN6")
		(34 "In16.Cu" signal "GND7")
		(2 "B.Cu" signal "BOTTOM")
		(9 "F.Adhes" user "F.Adhesive")
		(11 "B.Adhes" user "B.Adhesive")
		(13 "F.Paste" user "Package Geometry/Pastemask Top")
		(15 "B.Paste" user "Package Geometry/Pastemask Bottom")
		(5 "F.SilkS" user "Ref Des/Silkscreen Top")
		(7 "B.SilkS" user "Ref Des/Silkscreen Bottom")
		(1 "F.Mask" user "Board Geometry/Soldermask Top")
		(3 "B.Mask" user "Board Geometry/Soldermask Bottom")
		(17 "Dwgs.User" user "User.Drawings")
		(19 "Cmts.User" user "User.Comments")
		(21 "Eco1.User" user "User.Eco1")
		(23 "Eco2.User" user "User.Eco2")
		(25 "Edge.Cuts" user "Board Geometry/Outline")
		(27 "Margin" user)
		(31 "F.CrtYd" user "Package Geometry/Place Bound Top")
		(29 "B.CrtYd" user "Package Geometry/Place Bound Bottom")
		(35 "F.Fab" user "Ref Des/Assembly Top")
		(33 "B.Fab" user "Ref Des/Assembly Bottom")
	)
	(footprint ""
		(layer "B.Cu")
		(at 335.288128 -190.82893 90)
		(property "Reference" "R23"
			(at 0 0 90)
			(layer "B.SilkS")
			(hide yes)
			(effects
				(font
					(size 1.27 1.27)
				)
				(justify mirror)
			)
		)
		(property "Value" ""
			(at 0 0 90)
			(layer "B.Fab")
			(effects
				(font
					(size 1.27 1.27)
				)
				(justify mirror)
			)
		)
		(duplicate_pad_numbers_are_jumpers no)
		(fp_line
			(start 0.7874 -0.4064)
			(end -0.7874 -0.4064)
			(stroke
				(width 0.1524)
				(type default)
			)
			(layer "B.SilkS")
		)
		(fp_line
			(start -0.7874 -0.4064)
			(end -0.7874 0.4064)
			(stroke
				(width 0.1524)
				(type default)
			)
			(layer "B.SilkS")
		)
		(fp_line
			(start 0.7874 0.4064)
			(end 0.7874 -0.4064)
			(stroke
				(width 0.1524)
				(type default)
			)
			(layer "B.SilkS")
		)
		(fp_line
			(start -0.7874 0.4064)
			(end 0.7874 0.4064)
			(stroke
				(width 0.1524)
				(type default)
			)
			(layer "B.SilkS")
		)
		(fp_line
			(start 0.67945 -0.305054)
			(end 0.12065 -0.305054)
			(stroke
				(width 0.1)
				(type default)
			)
			(layer "B.Fab")
		)
		(fp_line
			(start 0.12065 -0.305054)
			(end 0.12065 -0.2794)
			(stroke
				(width 0.1)
				(type default)
			)
			(layer "B.Fab")
		)
		(fp_line
			(start -0.12065 -0.3048)
			(end -0.67945 -0.3048)
			(stroke
				(width 0.1)
				(type default)
			)
			(layer "B.Fab")
		)
		(fp_line
			(start -0.67945 -0.3048)
			(end -0.67945 0.3048)
			(stroke
				(width 0.1)
				(type default)
			)
			(layer "B.Fab")
		)
		(fp_line
			(start 0.12065 -0.2794)
			(end -0.12065 -0.2794)
			(stroke
				(width 0.1)
				(type default)
			)
			(layer "B.Fab")
		)
		(fp_line
			(start -0.12065 -0.2794)
			(end -0.12065 -0.3048)
			(stroke
				(width 0.1)
				(type default)
			)
			(layer "B.Fab")
		)
		(fp_line
			(start 0.12065 0.2794)
			(end 0.12065 0.3048)
			(stroke
				(width 0.1)
				(type default)
			)
			(layer "B.Fab")
		)
		(fp_line
			(start -0.120396 0.2794)
			(end 0.12065 0.2794)
			(stroke
				(width 0.1)
				(type default)
			)
			(layer "B.Fab")
		)
		(fp_line
			(start 0.67945 0.3048)
			(end 0.67945 -0.305054)
			(stroke
				(width 0.1)
				(type default)
			)
			(layer "B.Fab")
		)
		(fp_line
			(start 0.12065 0.3048)
			(end 0.67945 0.3048)
			(stroke
				(width 0.1)
				(type default)
			)
			(layer "B.Fab")
		)
		(fp_line
			(start -0.120396 0.3048)
			(end -0.120396 0.2794)
			(stroke
				(width 0.1)
				(type default)
			)
			(layer "B.Fab")
		)
		(fp_line
			(start -0.67945 0.3048)
			(end -0.120396 0.3048)
			(stroke
				(width 0.1)
				(type default)
			)
			(layer "B.Fab")
		)
		(pad "1" smd circle
			(at 0.40005 0 270)
			(size 0 0)
			(layers "B.Cu" "B.Mask" "B.Paste")
			(net "DBP_CPU0_MBP1_GTL_R_N")
		)
		(pad "2" smd circle
			(at -0.40005 0 270)
			(size 0 0)
			(layers "B.Cu" "B.Mask" "B.Paste")
			(net "DBP_CPU_MBP1_GTL_N")
		)
	)
	(footprint ""
		(layer "B.Cu")
		(at 258.023614 -321.524376 -90)
		(property "Reference" "C22"
			(at 0 0 90)
			(layer "B.SilkS")
			(hide yes)
			(effects
				(font
					(size 1.27 1.27)
				)
				(justify mirror)
			)
		)
		(property "Value" ""
			(at 0 0 90)
			(layer "B.Fab")
			(effects
				(font
					(size 1.27 1.27)
				)
				(justify mirror)
			)
		)
		(duplicate_pad_numbers_are_jumpers no)
		(fp_line
			(start -1.524 0.762)
			(end 1.524 0.762)
			(stroke
				(width 0.1524)
				(type default)
			)
			(layer "B.SilkS")
		)
		(fp_line
			(start 1.524 0.762)
			(end 1.524 -0.762)
			(stroke
				(width 0.1524)
				(type default)
			)
			(layer "B.SilkS")
		)
		(fp_line
			(start -1.524 -0.762)
			(end -1.524 0.762)
			(stroke
				(width 0.1524)
				(type default)
			)
			(layer "B.SilkS")
		)
		(fp_line
			(start 1.524 -0.762)
			(end -1.524 -0.762)
			(stroke
				(width 0.1524)
				(type default)
			)
			(layer "B.SilkS")
		)
		(fp_line
			(start -1.1049 0.724916)
			(end -1.1049 -0.724916)
			(stroke
				(width 0.1)
				(type default)
			)
			(layer "B.Fab")
		)
		(fp_line
			(start 1.1049 0.724916)
			(end -1.1049 0.724916)
			(stroke
				(width 0.1)
				(type default)
			)
			(layer "B.Fab")
		)
		(fp_line
			(start -1.1049 -0.724916)
			(end 1.1049 -0.724916)
			(stroke
				(width 0.1)
				(type default)
			)
			(layer "B.Fab")
		)
		(fp_line
			(start 1.1049 -0.724916)
			(end 1.1049 0.724916)
			(stroke
				(width 0.1)
				(type default)
			)
			(layer "B.Fab")
		)
		(pad "1" smd rect
			(at 0.889 0 270)
			(size 1.016 1.27)
			(layers "B.Cu" "B.Mask" "B.Paste")
			(net "P12V_S3_AUX_CPU0_NVDIMM")
		)
		(pad "2" smd rect
			(at -0.889 0 270)
			(size 1.016 1.27)
			(layers "B.Cu" "B.Mask" "B.Paste")
			(net "GND")
		)
	)
	(footprint ""
		(layer "B.Cu")
		(at 339.244686 -46.499272 180)
		(property "Reference" "C1205"
			(at 0 0 0)
			(layer "B.SilkS")
			(hide yes)
			(effects
				(font
					(size 1.27 1.27)
				)
				(justify mirror)
			)
		)
		(property "Value" ""
			(at 0 0 0)
			(layer "B.Fab")
			(effects
				(font
					(size 1.27 1.27)
				)
				(justify mirror)
			)
		)
		(duplicate_pad_numbers_are_jumpers no)
		(fp_line
			(start 0.7874 0.4064)
			(end 0.7874 -0.4064)
			(stroke
				(width 0.1524)
				(type default)
			)
			(layer "B.SilkS")
		)
		(fp_line
			(start 0.7874 -0.4064)
			(end -0.7874 -0.4064)
			(stroke
				(width 0.1524)
				(type default)
			)
			(layer "B.SilkS")
		)
		(fp_line
			(start -0.7874 0.4064)
			(end 0.7874 0.4064)
			(stroke
				(width 0.1524)
				(type default)
			)
			(layer "B.SilkS")
		)
		(fp_line
			(start -0.7874 -0.4064)
			(end -0.7874 0.4064)
			(stroke
				(width 0.1524)
				(type default)
			)
			(layer "B.SilkS")
		)
		(fp_line
			(start 0.67945 0.3048)
			(end 0.67945 -0.305054)
			(stroke
				(width 0.1)
				(type default)
			)
			(layer "B.Fab")
		)
		(fp_line
			(start 0.67945 -0.305054)
			(end 0.12065 -0.305054)
			(stroke
				(width 0.1)
				(type default)
			)
			(layer "B.Fab")
		)
		(fp_line
			(start 0.12065 0.3048)
			(end 0.67945 0.3048)
			(stroke
				(width 0.1)
				(type default)
			)
			(layer "B.Fab")
		)
		(fp_line
			(start 0.12065 0.2794)
			(end 0.12065 0.3048)
			(stroke
				(width 0.1)
				(type default)
			)
			(layer "B.Fab")
		)
		(fp_line
			(start 0.12065 -0.2794)
			(end -0.12065 -0.2794)
			(stroke
				(width 0.1)
				(type default)
			)
			(layer "B.Fab")
		)
		(fp_line
			(start 0.12065 -0.305054)
			(end 0.12065 -0.2794)
			(stroke
				(width 0.1)
				(type default)
			)
			(layer "B.Fab")
		)
		(fp_line
			(start -0.120396 0.3048)
			(end -0.120396 0.2794)
			(stroke
				(width 0.1)
				(type default)
			)
			(layer "B.Fab")
		)
		(fp_line
			(start -0.120396 0.2794)
			(end 0.12065 0.2794)
			(stroke
				(width 0.1)
				(type default)
			)
			(layer "B.Fab")
		)
		(fp_line
			(start -0.12065 -0.2794)
			(end -0.12065 -0.3048)
			(stroke
				(width 0.1)
				(type default)
			)
			(layer "B.Fab")
		)
		(fp_line
			(start -0.12065 -0.3048)
			(end -0.67945 -0.3048)
			(stroke
				(width 0.1)
				(type default)
			)
			(layer "B.Fab")
		)
		(fp_line
			(start -0.67945 0.3048)
			(end -0.120396 0.3048)
			(stroke
				(width 0.1)
				(type default)
			)
			(layer "B.Fab")
		)
		(fp_line
			(start -0.67945 -0.3048)
			(end -0.67945 0.3048)
			(stroke
				(width 0.1)
				(type default)
			)
			(layer "B.Fab")
		)
		(pad "1" smd circle
			(at 0.40005 0)
			(size 0 0)
			(layers "B.Cu" "B.Mask" "B.Paste")
			(net "P1V05_PCH_AUX")
		)
		(pad "2" smd circle
			(at -0.40005 0)
			(size 0 0)
			(layers "B.Cu" "B.Mask" "B.Paste")
			(net "GND")
		)
	)
	(footprint ""
		(layer "B.Cu")
		(at 62.996572 -144.44726)
		(property "Reference" "PC456_P1_2"
			(at 0 0 0)
			(layer "B.SilkS")
			(hide yes)
			(effects
				(font
					(size 1.27 1.27)
				)
				(justify mirror)
			)
		)
		(property "Value" ""
			(at 0 0 0)
			(layer "B.Fab")
			(effects
				(font
					(size 1.27 1.27)
				)
				(justify mirror)
			)
		)
		(duplicate_pad_numbers_are_jumpers no)
		(fp_line
			(start -1.524 -0.762)
			(end -1.524 0.762)
			(stroke
				(width 0.1524)
				(type default)
			)
			(layer "B.SilkS")
		)
		(fp_line
			(start -1.524 0.762)
			(end 1.524 0.762)
			(stroke
				(width 0.1524)
				(type default)
			)
			(layer "B.SilkS")
		)
		(fp_line
			(start 1.524 -0.762)
			(end -1.524 -0.762)
			(stroke
				(width 0.1524)
				(type default)
			)
			(layer "B.SilkS")
		)
		(fp_line
			(start 1.524 0.762)
			(end 1.524 -0.762)
			(stroke
				(width 0.1524)
				(type default)
			)
			(layer "B.SilkS")
		)
		(fp_line
			(start -1.1049 -0.724916)
			(end 1.1049 -0.724916)
			(stroke
				(width 0.1)
				(type default)
			)
			(layer "B.Fab")
		)
		(fp_line
			(start -1.1049 0.724916)
			(end -1.1049 -0.724916)
			(stroke
				(width 0.1)
				(type default)
			)
			(layer "B.Fab")
		)
		(fp_line
			(start 1.1049 -0.724916)
			(end 1.1049 0.724916)
			(stroke
				(width 0.1)
				(type default)
			)
			(layer "B.Fab")
		)
		(fp_line
			(start 1.1049 0.724916)
			(end -1.1049 0.724916)
			(stroke
				(width 0.1)
				(type default)
			)
			(layer "B.Fab")
		)
		(pad "1" smd rect
			(at 0.889 0)
			(size 1.016 1.27)
			(layers "B.Cu" "B.Mask" "B.Paste")
			(net "PVCCINFAON_CPU1")
		)
		(pad "2" smd rect
			(at -0.889 0)
			(size 1.016 1.27)
			(layers "B.Cu" "B.Mask" "B.Paste")
			(net "GND")
		)
	)
	(footprint ""
		(layer "B.Cu")
		(at 428.413926 -127.578866)
		(property "Reference" "PR372"
			(at 0 0 0)
			(layer "B.SilkS")
			(hide yes)
			(effects
				(font
					(size 1.27 1.27)
				)
				(justify mirror)
			)
		)
		(property "Value" ""
			(at 0 0 0)
			(layer "B.Fab")
			(effects
				(font
					(size 1.27 1.27)
				)
				(justify mirror)
			)
		)
		(duplicate_pad_numbers_are_jumpers no)
		(fp_line
			(start -0.7874 -0.4064)
			(end -0.7874 0.4064)
			(stroke
				(width 0.1524)
				(type default)
			)
			(layer "B.SilkS")
		)
		(fp_line
			(start -0.7874 0.4064)
			(end 0.7874 0.4064)
			(stroke
				(width 0.1524)
				(type default)
			)
			(layer "B.SilkS")
		)
		(fp_line
			(start 0.7874 -0.4064)
			(end -0.7874 -0.4064)
			(stroke
				(width 0.1524)
				(type default)
			)
			(layer "B.SilkS")
		)
		(fp_line
			(start 0.7874 0.4064)
			(end 0.7874 -0.4064)
			(stroke
				(width 0.1524)
				(type default)
			)
			(layer "B.SilkS")
		)
		(fp_line
			(start -0.67945 -0.3048)
			(end -0.67945 0.3048)
			(stroke
				(width 0.1)
				(type default)
			)
			(layer "B.Fab")
		)
		(fp_line
			(start -0.67945 0.3048)
			(end -0.120396 0.3048)
			(stroke
				(width 0.1)
				(type default)
			)
			(layer "B.Fab")
		)
		(fp_line
			(start -0.12065 -0.3048)
			(end -0.67945 -0.3048)
			(stroke
				(width 0.1)
				(type default)
			)
			(layer "B.Fab")
		)
		(fp_line
			(start -0.12065 -0.2794)
			(end -0.12065 -0.3048)
			(stroke
				(width 0.1)
				(type default)
			)
			(layer "B.Fab")
		)
		(fp_line
			(start -0.120396 0.2794)
			(end 0.12065 0.2794)
			(stroke
				(width 0.1)
				(type default)
			)
			(layer "B.Fab")
		)
		(fp_line
			(start -0.120396 0.3048)
			(end -0.120396 0.2794)
			(stroke
				(width 0.1)
				(type default)
			)
			(layer "B.Fab")
		)
		(fp_line
			(start 0.12065 -0.305054)
			(end 0.12065 -0.2794)
			(stroke
				(width 0.1)
				(type default)
			)
			(layer "B.Fab")
		)
		(fp_line
			(start 0.12065 -0.2794)
			(end -0.12065 -0.2794)
			(stroke
				(width 0.1)
				(type default)
			)
			(layer "B.Fab")
		)
		(fp_line
			(start 0.12065 0.2794)
			(end 0.12065 0.3048)
			(stroke
				(width 0.1)
				(type default)
			)
			(layer "B.Fab")
		)
		(fp_line
			(start 0.12065 0.3048)
			(end 0.67945 0.3048)
			(stroke
				(width 0.1)
				(type default)
			)
			(layer "B.Fab")
		)
		(fp_line
			(start 0.67945 -0.305054)
			(end 0.12065 -0.305054)
			(stroke
				(width 0.1)
				(type default)
			)
			(layer "B.Fab")
		)
		(fp_line
			(start 0.67945 0.3048)
			(end 0.67945 -0.305054)
			(stroke
				(width 0.1)
				(type default)
			)
			(layer "B.Fab")
		)
		(pad "1" smd circle
			(at 0.40005 0 180)
			(size 0 0)
			(layers "B.Cu" "B.Mask" "B.Paste")
			(net "P3V3_AUX")
		)
		(pad "2" smd circle
			(at -0.40005 0 180)
			(size 0 0)
			(layers "B.Cu" "B.Mask" "B.Paste")
			(net "PVCCD_HV_CPU0_FAULT")
		)
	)
	(footprint ""
		(layer "B.Cu")
		(at 255.064006 -102.285292 90)
		(property "Reference" "C1312"
			(at 0 0 90)
			(layer "B.SilkS")
			(hide yes)
			(effects
				(font
					(size 1.27 1.27)
				)
				(justify mirror)
			)
		)
		(property "Value" ""
			(at 0 0 90)
			(layer "B.Fab")
			(effects
				(font
					(size 1.27 1.27)
				)
				(justify mirror)
			)
		)
		(duplicate_pad_numbers_are_jumpers no)
		(fp_line
			(start 0.7874 -0.4064)
			(end -0.7874 -0.4064)
			(stroke
				(width 0.1524)
				(type default)
			)
			(layer "B.SilkS")
		)
		(fp_line
			(start -0.7874 -0.4064)
			(end -0.7874 0.4064)
			(stroke
				(width 0.1524)
				(type default)
			)
			(layer "B.SilkS")
		)
		(fp_line
			(start 0.7874 0.4064)
			(end 0.7874 -0.4064)
			(stroke
				(width 0.1524)
				(type default)
			)
			(layer "B.SilkS")
		)
		(fp_line
			(start -0.7874 0.4064)
			(end 0.7874 0.4064)
			(stroke
				(width 0.1524)
				(type default)
			)
			(layer "B.SilkS")
		)
		(fp_line
			(start 0.67945 -0.305054)
			(end 0.12065 -0.305054)
			(stroke
				(width 0.1)
				(type default)
			)
			(layer "B.Fab")
		)
		(fp_line
			(start 0.12065 -0.305054)
			(end 0.12065 -0.2794)
			(stroke
				(width 0.1)
				(type default)
			)
			(layer "B.Fab")
		)
		(fp_line
			(start -0.12065 -0.3048)
			(end -0.67945 -0.3048)
			(stroke
				(width 0.1)
				(type default)
			)
			(layer "B.Fab")
		)
		(fp_line
			(start -0.67945 -0.3048)
			(end -0.67945 0.3048)
			(stroke
				(width 0.1)
				(type default)
			)
			(layer "B.Fab")
		)
		(fp_line
			(start 0.12065 -0.2794)
			(end -0.12065 -0.2794)
			(stroke
				(width 0.1)
				(type default)
			)
			(layer "B.Fab")
		)
		(fp_line
			(start -0.12065 -0.2794)
			(end -0.12065 -0.3048)
			(stroke
				(width 0.1)
				(type default)
			)
			(layer "B.Fab")
		)
		(fp_line
			(start 0.12065 0.2794)
			(end 0.12065 0.3048)
			(stroke
				(width 0.1)
				(type default)
			)
			(layer "B.Fab")
		)
		(fp_line
			(start -0.120396 0.2794)
			(end 0.12065 0.2794)
			(stroke
				(width 0.1)
				(type default)
			)
			(layer "B.Fab")
		)
		(fp_line
			(start 0.67945 0.3048)
			(end 0.67945 -0.305054)
			(stroke
				(width 0.1)
				(type default)
			)
			(layer "B.Fab")
		)
		(fp_line
			(start 0.12065 0.3048)
			(end 0.67945 0.3048)
			(stroke
				(width 0.1)
				(type default)
			)
			(layer "B.Fab")
		)
		(fp_line
			(start -0.120396 0.3048)
			(end -0.120396 0.2794)
			(stroke
				(width 0.1)
				(type default)
			)
			(layer "B.Fab")
		)
		(fp_line
			(start -0.67945 0.3048)
			(end -0.120396 0.3048)
			(stroke
				(width 0.1)
				(type default)
			)
			(layer "B.Fab")
		)
		(pad "1" smd circle
			(at 0.40005 0 270)
			(size 0 0)
			(layers "B.Cu" "B.Mask" "B.Paste")
			(net "P3V3_AUX_CLK_GEN_VDDMXCK_CK440")
		)
		(pad "2" smd circle
			(at -0.40005 0 270)
			(size 0 0)
			(layers "B.Cu" "B.Mask" "B.Paste")
			(net "GND")
		)
	)
	(footprint ""
		(layer "B.Cu")
		(at 324.19163 -25.68702 90)
		(property "Reference" "R1996"
			(at 0 0 90)
			(layer "B.SilkS")
			(hide yes)
			(effects
				(font
					(size 1.27 1.27)
				)
				(justify mirror)
			)
		)
		(property "Value" ""
			(at 0 0 90)
			(layer "B.Fab")
			(effects
				(font
					(size 1.27 1.27)
				)
				(justify mirror)
			)
		)
		(duplicate_pad_numbers_are_jumpers no)
		(fp_line
			(start 0.7874 -0.4064)
			(end -0.7874 -0.4064)
			(stroke
				(width 0.1524)
				(type default)
			)
			(layer "B.SilkS")
		)
		(fp_line
			(start -0.7874 -0.4064)
			(end -0.7874 0.4064)
			(stroke
				(width 0.1524)
				(type default)
			)
			(layer "B.SilkS")
		)
		(fp_line
			(start 0.7874 0.4064)
			(end 0.7874 -0.4064)
			(stroke
				(width 0.1524)
				(type default)
			)
			(layer "B.SilkS")
		)
		(fp_line
			(start -0.7874 0.4064)
			(end 0.7874 0.4064)
			(stroke
				(width 0.1524)
				(type default)
			)
			(layer "B.SilkS")
		)
		(fp_line
			(start 0.67945 -0.305054)
			(end 0.12065 -0.305054)
			(stroke
				(width 0.1)
				(type default)
			)
			(layer "B.Fab")
		)
		(fp_line
			(start 0.12065 -0.305054)
			(end 0.12065 -0.2794)
			(stroke
				(width 0.1)
				(type default)
			)
			(layer "B.Fab")
		)
		(fp_line
			(start -0.12065 -0.3048)
			(end -0.67945 -0.3048)
			(stroke
				(width 0.1)
				(type default)
			)
			(layer "B.Fab")
		)
		(fp_line
			(start -0.67945 -0.3048)
			(end -0.67945 0.3048)
			(stroke
				(width 0.1)
				(type default)
			)
			(layer "B.Fab")
		)
		(fp_line
			(start 0.12065 -0.2794)
			(end -0.12065 -0.2794)
			(stroke
				(width 0.1)
				(type default)
			)
			(layer "B.Fab")
		)
		(fp_line
			(start -0.12065 -0.2794)
			(end -0.12065 -0.3048)
			(stroke
				(width 0.1)
				(type default)
			)
			(layer "B.Fab")
		)
		(fp_line
			(start 0.12065 0.2794)
			(end 0.12065 0.3048)
			(stroke
				(width 0.1)
				(type default)
			)
			(layer "B.Fab")
		)
		(fp_line
			(start -0.120396 0.2794)
			(end 0.12065 0.2794)
			(stroke
				(width 0.1)
				(type default)
			)
			(layer "B.Fab")
		)
		(fp_line
			(start 0.67945 0.3048)
			(end 0.67945 -0.305054)
			(stroke
				(width 0.1)
				(type default)
			)
			(layer "B.Fab")
		)
		(fp_line
			(start 0.12065 0.3048)
			(end 0.67945 0.3048)
			(stroke
				(width 0.1)
				(type default)
			)
			(layer "B.Fab")
		)
		(fp_line
			(start -0.120396 0.3048)
			(end -0.120396 0.2794)
			(stroke
				(width 0.1)
				(type default)
			)
			(layer "B.Fab")
		)
		(fp_line
			(start -0.67945 0.3048)
			(end -0.120396 0.3048)
			(stroke
				(width 0.1)
				(type default)
			)
			(layer "B.Fab")
		)
		(pad "1" smd circle
			(at 0.40005 0 270)
			(size 0 0)
			(layers "B.Cu" "B.Mask" "B.Paste")
			(net "FM_PCH_SLP_S4_N")
		)
		(pad "2" smd circle
			(at -0.40005 0 270)
			(size 0 0)
			(layers "B.Cu" "B.Mask" "B.Paste")
			(net "FM_SLPS4_PLD_N")
		)
	)
)
